FILE_TYPE = CONNECTIVITY;
{Allegro Design Entry HDL 17.4-2019 S026 (4007227) 1/17/2022}
"PAGE_NUMBER" = 181;
0"NC";
1"GND\g";
2"GND\g";
3"GND\g";
4"GND\g";
5"GND\g";
6"GND\g";
7"GND\g";
8"GND\g";
9"GND\g";
10"GND\g";
11"GND\g";
12"SW_P12V_AUX_PVDDIO_P0_FLT\g";
13"GND\g";
14"GND\g";
15"PVDDIO_P0_VCC3"CDS_PHYS_NET_NAME"PVDDIO_P0_VCC3";
16"SW_PVDDIO_P0_BOOT3";
17"SW_PVDDIO_P0_BOOT3_R";
18"SW_PVDDIO_P0_BOOT4";
19"SW_PVDDIO_P0_BOOT4_R";
20"PVDDCR_CPU1_P0_PVCC\g";
21"GND\g";
22"PVDDCR_CPU1_P0_PVCC\g";
23"GND\g";
24"GND\g";
25"PVDDIO_P0\g";
26"GND\g";
27"PVDDIO_P0\g";
28"NC_PVDDIO_P0_DNC3";
29"PVDDCR_CPU1_P0_VCCS"CDS_PHYS_NET_NAME"PVDDCR_CPU1_P0_VCCS";
30"PVDDIO_P0_LSET4";
31"PVDDCR_CPU1_P0_VCCS"CDS_PHYS_NET_NAME"PVDDCR_CPU1_P0_VCCS";
32"PVDDIO_P0_TEMP1";
33"NC_PVDDIO_P0_DNC4";
34"PVDDIO_P0_PWM4";
35"PVDDIO_P0_IMON4";
36"NC_PVDDIO_P0_GL1_4";
37"NC_PVDDIO_P0_GL2_4";
38"PVDDIO_P0_VOS4";
39"PVDDIO_P0_VCC4"CDS_PHYS_NET_NAME"PVDDIO_P0_VCC4";
40"PVDDIO_P0_LSET3"CDS_PHYS_NET_NAME"PVDDIO_P0_LSET3";
41"PVDDIO_P0_PWM3";
42"PVDDIO_P0_TEMP1";
43"PVDDIO_P0_IMON3";
44"NC_PVDDIO_P0_GL2_3";
45"NC_PVDDIO_P0_GL1_3";
46"SW_PVDDIO_P0_SW4_RC";
47"IND_PVDDIO_P0_CPL0";
48"IND_PVDDIO_P0_CPL4";
49"SW_PVDDIO_P0_SW3_RC";
50"IND_PVDDIO_P0_CPL4";
51"IND_PVDDIO_P0_CPL3";
52"SW_PVDDIO_P0_SW4";
53"SW_PVDDIO_P0_BOOTR4";
54"SW_PVDDIO_P0_BOOTR3";
55"PVDDIO_P0_VOS3";
56"SW_PVDDIO_P0_SW3";
57"SW_P12V_AUX_PVDDIO_P0_FLT\g";
%"Q_CAP"
"1","(-11900,2250)","0","pure_quanta","I1";
;
LOCATION"PC176_10"
$SEC"1"
CDS_SEC"1"
VALUE"0.1UF"
PACK_TYPE"0402"
VOLTAGE"25V"
TOLERANCE"10%"
MATERIAL"X7R"
CDS_LIB"pure_quanta"
PART_NUMBER"CH4104K1B00";
"B"
$PN"2"3;
"A"
$PN"1"31;
%"Q_CAP"
"1","(-11050,3025)","0","pure_quanta","I10";
;
LOCATION"PC171"
$SEC"1"
CDS_SEC"1"
PACK_TYPE"C0402"
VOLTAGE"10V"
VALUE"2.2UF"
TOLERANCE"10%"
MATERIAL"X6S"
CDS_LIB"pure_quanta"
PART_NUMBER"CH5222KEB01";
"B"
$PN"2"11;
"A"
$PN"1"39;
%"UNIVERSAL_GND"
"1","(-10700,3325)","0","pure_quanta_power","I11";
;
CDS_LIB"pure_quanta_power"
HDL_POWER"GND";
"A"1;
%"Q_RES"
"2","(-11050,3575)","0","pure_quanta","I12";
;
LOCATION"PR107"
$SEC"1"
CDS_SEC"1"
WATTAGE"1/16W"
MATERIAL"CHIP"
TOLERANCE"1%"
VALUE"2.2"
PACK_TYPE"0402LF"
CDS_LIB"pure_quanta"
PART_NUMBER"CS-2202FB01";
"A"
$PN"1"20;
"B"
$PN"2"39;
%"Q_CAP"
"1","(-10700,3600)","0","pure_quanta","I13";
;
LOCATION"PC173_IOP0_4"
$SEC"1"
CDS_SEC"1"
PACK_TYPE"C0402"
VOLTAGE"10V"
VALUE"2.2UF"
TOLERANCE"10%"
MATERIAL"X6S"
CDS_LIB"pure_quanta"
PART_NUMBER"CH5222KEB01";
"B"
$PN"2"1;
"A"
$PN"1"20;
%"VCC_CORE"
"1","(-11050,4000)","0","pure_quanta_power","I14";
;
HDL_POWER"PVDDCR_CPU1_P0_PVCC"
CDS_LIB"pure_quanta_power";
"A"20;
%"UNIVERSAL_GND"
"1","(-8700,1900)","0","pure_quanta_power","I15";
;
CDS_LIB"pure_quanta_power"
HDL_POWER"GND";
"A"21;
%"Q_RES"
"1","(-8225,2975)","0","pure_quanta","I16";
;
LOCATION"PR109"
$SEC"1"
CDS_SEC"1"
MATERIAL"CHIP"
PACK_TYPE"0402LF"
TOLERANCE"1%"
WATTAGE"1/16W"
VALUE"5.6"
CDS_LIB"pure_quanta"
PART_NUMBER"CS-5602FB01";
"B"
$PN"2"19;
"A"
$PN"1"18;
%"Q_CAP"
"1","(-8475,3600)","0","pure_quanta","I17";
;
LOCATION"PC178_4"
$SEC"1"
CDS_SEC"1"
PACK_TYPE"0402"
VOLTAGE"25V"
VALUE"0.1UF"
TOLERANCE"10%"
MATERIAL"X7R"
CDS_LIB"pure_quanta"
PART_NUMBER"CH4104K1B00";
"B"
$PN"2"13;
"A"
$PN"1"12;
%"UNIVERSAL_GND"
"1","(-11925,4850)","0","pure_quanta_power","I18";
;
CDS_LIB"pure_quanta_power"
HDL_POWER"GND";
"A"2;
%"Q_CAP"
"1","(-11925,5050)","0","pure_quanta","I19";
;
LOCATION"PC175_9"
$SEC"1"
CDS_SEC"1"
PACK_TYPE"0402"
VOLTAGE"25V"
VALUE"0.1UF"
TOLERANCE"10%"
MATERIAL"X7R"
CDS_LIB"pure_quanta"
PART_NUMBER"CH4104K1B00";
"B"
$PN"2"2;
"A"
$PN"1"29;
%"UNIVERSAL_GND"
"1","(-11900,2050)","0","pure_quanta_power","I2";
;
CDS_LIB"pure_quanta_power"
HDL_POWER"GND";
"A"3;
%"UNIVERSAL_GND"
"1","(-11350,4750)","0","pure_quanta_power","I20";
;
CDS_LIB"pure_quanta_power"
HDL_POWER"GND";
"A"4;
%"Q_RES"
"2","(-11350,4975)","2","pure_quanta","I21";
;
LOCATION"PR106"
$SEC"1"
CDS_SEC"1"
PACK_TYPE"0402LF"
MATERIAL"EMPTY"
WATTAGE"1/16W"
TOLERANCE"1%"
VALUE"8.87K"
CDS_LIB"pure_quanta"
PART_NUMBER"CS28872FB01";
"A"
$PN"1"40;
"B"
$PN"2"4;
%"UNIVERSAL_GND"
"1","(-11025,5525)","0","pure_quanta_power","I26";
;
CDS_LIB"pure_quanta_power"
HDL_POWER"GND";
"A"5;
%"Q_CAP"
"1","(-11025,5725)","0","pure_quanta","I27";
;
LOCATION"PC172"
$SEC"1"
CDS_SEC"1"
PACK_TYPE"C0402"
VOLTAGE"10V"
VALUE"2.2UF"
TOLERANCE"10%"
MATERIAL"X6S"
CDS_LIB"pure_quanta"
PART_NUMBER"CH5222KEB01";
"B"
$PN"2"5;
"A"
$PN"1"15;
%"Q_RES"
"2","(-11025,6275)","0","pure_quanta","I28";
;
LOCATION"PR108"
$SEC"1"
CDS_SEC"1"
WATTAGE"1/16W"
MATERIAL"CHIP"
TOLERANCE"1%"
VALUE"2.2"
PACK_TYPE"0402LF"
CDS_LIB"pure_quanta"
PART_NUMBER"CS-2202FB01";
"A"
$PN"1"22;
"B"
$PN"2"15;
%"UNIVERSAL_GND"
"1","(-10675,6025)","0","pure_quanta_power","I29";
;
CDS_LIB"pure_quanta_power"
HDL_POWER"GND";
"A"6;
%"UNIVERSAL_GND"
"1","(-11375,1900)","0","pure_quanta_power","I3";
;
CDS_LIB"pure_quanta_power"
HDL_POWER"GND";
"A"7;
%"Q_CAP"
"1","(-10675,6300)","0","pure_quanta","I30";
;
LOCATION"PC174_IOP0_3"
$SEC"1"
CDS_SEC"1"
PACK_TYPE"C0402"
VOLTAGE"10V"
VALUE"2.2UF"
TOLERANCE"10%"
MATERIAL"X6S"
CDS_LIB"pure_quanta"
PART_NUMBER"CH5222KEB01";
"B"
$PN"2"6;
"A"
$PN"1"22;
%"VCC_CORE"
"1","(-11025,6700)","0","pure_quanta_power","I31";
;
HDL_POWER"PVDDCR_CPU1_P0_PVCC"
CDS_LIB"pure_quanta_power";
"A"22;
%"ISL99390FRZTR5935"
"1","(-9350,5425)","0","pure_quanta","I32";
;
LOCATION"PU19"
$SEC"1"
CDS_SEC"1"
VALUE"ISL99390FRZ-TR5935"
MATERIAL"IC"
PART_TYPE"SMLF"
CDS_LIB"pure_quanta"
NEEDS_NO_SIZE"TRUE"
CDS_LMAN_SYM_OUTLINE"-300,700,250,-650"
PART_NUMBER"AL099390004";
"PGND2"
$PN"7_9-20_24"23;
"GL2"
$PN"41"44;
"GL1"
$PN"6"45;
"DNC"
$PN"31"28;
"EN"
$PN"35"15;
"PGND3"
$PN"40"23;
"VOS"
$PN"1"55;
"VIN2"
$PN"30"57;
"PGND1"
$PN"5"23;
"SW"
$PN"10_19"56;
"LSET"
$PN"37"40;
"IOUT"
$PN"38"43;
"TOUT_FLT"
$PN"36"42;
"PVCC"
$PN"4"22;
"PHASE"
$PN"32"54;
"VIN1"
$PN"25_29"57;
"BOOT"
$PN"33"16;
"AGND"
$PN"2"23;
"VCC"
$PN"3"15;
"REFIN"
$PN"39"29;
"PWM"
$PN"34"41;
%"UNIVERSAL_GND"
"1","(-8700,4700)","0","pure_quanta_power","I33";
;
CDS_LIB"pure_quanta_power"
HDL_POWER"GND";
"A"23;
%"Q_RES"
"1","(-8000,5775)","0","pure_quanta","I34";
;
LOCATION"PR110"
$SEC"1"
CDS_SEC"1"
PACK_TYPE"0402LF"
TOLERANCE"1%"
WATTAGE"1/16W"
MATERIAL"CHIP"
VALUE"5.6"
CDS_LIB"pure_quanta"
PART_NUMBER"CS-5602FB01";
"B"
$PN"2"17;
"A"
$PN"1"16;
%"Q_CAP"
"1","(-8500,6375)","0","pure_quanta","I35";
;
LOCATION"PC177_3"
$SEC"1"
CDS_SEC"1"
PACK_TYPE"0402"
VALUE"0.1UF"
TOLERANCE"10%"
MATERIAL"X7R"
VOLTAGE"25V"
CDS_LIB"pure_quanta"
PART_NUMBER"CH4104K1B00";
"B"
$PN"2"14;
"A"
$PN"1"57;
%"Q_CAP"
"1","(-8075,6375)","0","pure_quanta","I36";
;
LOCATION"PC179_3"
$SEC"1"
CDS_SEC"1"
VOLTAGE"25V"
VALUE"1UF"
TOLERANCE"10%"
MATERIAL"X6S"
PACK_TYPE"C0402"
CDS_LIB"pure_quanta"
PART_NUMBER"CH5104KEB02";
"B"
$PN"2"14;
"A"
$PN"1"57;
%"UNIVERSAL_GND"
"1","(-7950,1675)","0","pure_quanta_power","I37";
;
CDS_LIB"pure_quanta_power"
HDL_POWER"GND";
"A"8;
%"Q_RES"
"2","(-7950,1900)","0","pure_quanta","I38";
;
LOCATION"PR291"
$SEC"1"
CDS_SEC"1"
PACK_TYPE"0402LF"
VALUE"1.5"
TOLERANCE"1%"
MATERIAL"EMPTY"
WATTAGE"1/8W"
CDS_LIB"pure_quanta"
PART_NUMBER"CS-1504FB00";
"A"
$PN"1"46;
"B"
$PN"2"8;
%"Q_CAP"
"1","(-7950,2425)","0","pure_quanta","I39";
;
LOCATION"PC163"
$SEC"1"
CDS_SEC"1"
MATERIAL"EMPTY"
PACK_TYPE"C0402"
TOLERANCE"10%"
VOLTAGE"50V"
VALUE"560PF"
CDS_LIB"pure_quanta"
PART_NUMBER"CH1566K1B09";
"B"
$PN"2"46;
"A"
$PN"1"52;
%"Q_RES"
"2","(-11375,2125)","2","pure_quanta","I4";
;
LOCATION"PR105"
$SEC"1"
CDS_SEC"1"
WATTAGE"1/16W"
MATERIAL"EMPTY"
TOLERANCE"1%"
VALUE"8.87K"
PACK_TYPE"0402LF"
CDS_LIB"pure_quanta"
PART_NUMBER"CS28872FB01";
"A"
$PN"1"30;
"B"
$PN"2"7;
%"UNIVERSAL_GND"
"1","(-7525,2275)","0","pure_quanta_power","I40";
;
CDS_LIB"pure_quanta_power"
HDL_POWER"GND";
"A"9;
%"Q_RES"
"1","(-6800,1500)","0","pure_quanta","I41";
;
LOCATION"PR112"
$SEC"1"
CDS_SEC"1"
WATTAGE"1/16W"
MATERIAL"CHIP"
TOLERANCE"5%"
VALUE"0"
PACK_TYPE"0402LF"
CDS_LIB"pure_quanta"
PART_NUMBER"CS00002JB13";
"B"
$PN"2"25;
"A"
$PN"1"38;
%"Q_INDUCTOR4P_14"
"1","(-6275,2500)","0","pure_quanta","I42";
;
LOCATION"PL20"
$SEC"1"
CDS_SEC"1"
PART_TYPE"SMLF"
VALUE"150NH"
MATERIAL"IND"
NEEDS_NO_SIZE"TRUE"
CDS_LIB"pure_quanta"
PART_NUMBER"CV+15^0TZ04";
"1"
$PN"1"52;
"4"
$PN"4"25;
"3"
$PN"3"48;
"2"
$PN"2"47;
%"Q_INDUCTOR"
"1","(-7300,2400)","2","pure_quanta","I43";
;
LOCATION"PL16"
$SEC"1"
CDS_SEC"1"
MATERIAL"IND"
PACK_TYPE"SMLF"
VALUE"0.22UH/33A"
CDS_LIB"pure_quanta"
NEEDS_NO_SIZE"TRUE"
PART_NUMBER"CV+22Y0EZ00";
"1"
$PN"1"47;
"2"
$PN"2"9;
%"Q_CAP"
"1","(-7350,2850)","0","pure_quanta","I44";
;
LOCATION"PC183"
$SEC"1"
CDS_SEC"1"
PACK_TYPE"0402"
VOLTAGE"16V"
VALUE"0.22UF"
TOLERANCE"10%"
MATERIAL"X7R"
CDS_LIB"pure_quanta"
PART_NUMBER"CH4223K1B00";
"B"
$PN"2"53;
"A"
$PN"1"19;
%"Q_CAP"
"1","(-8000,3575)","0","pure_quanta","I45";
;
LOCATION"PC180_4"
$SEC"1"
CDS_SEC"1"
PACK_TYPE"C0402"
VOLTAGE"25V"
VALUE"1UF"
TOLERANCE"10%"
MATERIAL"X6S"
CDS_LIB"pure_quanta"
PART_NUMBER"CH5104KEB02";
"B"
$PN"2"13;
"A"
$PN"1"12;
%"Q_CAP"
"1","(-7600,3575)","0","pure_quanta","I46";
;
LOCATION"PC182_4"
$SEC"1"
CDS_SEC"1"
TOLERANCE"20%"
VOLTAGE"16V"
VALUE"22UF"
MATERIAL"X6S"
PACK_TYPE"C0805"
CDS_LIB"pure_quanta"
PART_NUMBER"CH6223MEA01";
"B"
$PN"2"13;
"A"
$PN"1"12;
%"Q_CAP"
"1","(-7200,3575)","0","pure_quanta","I47";
;
LOCATION"PC185_4"
$SEC"1"
CDS_SEC"1"
TOLERANCE"20%"
VOLTAGE"16V"
VALUE"22UF"
MATERIAL"X6S"
PACK_TYPE"C0805"
CDS_LIB"pure_quanta"
PART_NUMBER"CH6223MEA01";
"B"
$PN"2"13;
"A"
$PN"1"12;
%"UNIVERSAL_GND"
"1","(-6725,3200)","0","pure_quanta_power","I48";
;
CDS_LIB"pure_quanta_power"
HDL_POWER"GND";
"A"13;
%"Q_CAP"
"1","(-6725,3575)","0","pure_quanta","I49";
;
LOCATION"PC188_4"
$SEC"1"
CDS_SEC"1"
TOLERANCE"20%"
VOLTAGE"16V"
VALUE"22UF"
MATERIAL"X6S"
PACK_TYPE"C0805"
CDS_LIB"pure_quanta"
PART_NUMBER"CH6223MEA01";
"B"
$PN"2"13;
"A"
$PN"1"12;
%"Q_RES"
"1","(-6700,4300)","0","pure_quanta","I50";
;
LOCATION"PR111"
$SEC"1"
CDS_SEC"1"
WATTAGE"1/16W"
MATERIAL"CHIP"
VALUE"0"
PACK_TYPE"0402LF"
TOLERANCE"5%"
CDS_LIB"pure_quanta"
PART_NUMBER"CS00002JB13";
"B"
$PN"2"27;
"A"
$PN"1"55;
%"VCC_CORE"
"1","(-6725,3950)","0","pure_quanta_power","I51";
;
HDL_POWER"SW_P12V_AUX_PVDDIO_P0_FLT"
CDS_LIB"pure_quanta_power";
"A"12;
%"Q_CAP"
"1","(-4200,2425)","0","pure_quanta","I53";
;
LOCATION"PC189_4"
$SEC"1"
CDS_SEC"1"
PACK_TYPE"C0805"
MATERIAL"X6S"
TOLERANCE"20%"
VALUE"22UF"
VOLTAGE"4V"
CDS_LIB"pure_quanta"
PART_NUMBER"CH622KMEA03";
"B"
$PN"2"24;
"A"
$PN"1"25;
%"UNIVERSAL_GND"
"1","(-7950,4475)","0","pure_quanta_power","I54";
;
CDS_LIB"pure_quanta_power"
HDL_POWER"GND";
"A"10;
%"Q_RES"
"2","(-7950,4700)","0","pure_quanta","I55";
;
LOCATION"PR379"
$SEC"1"
CDS_SEC"1"
PACK_TYPE"0402LF"
TOLERANCE"1%"
WATTAGE"1/8W"
VALUE"1.5"
MATERIAL"EMPTY"
CDS_LIB"pure_quanta"
PART_NUMBER"CS-1504FB00";
"A"
$PN"1"49;
"B"
$PN"2"10;
%"Q_CAP"
"1","(-7950,5225)","0","pure_quanta","I56";
;
LOCATION"PC166"
$SEC"1"
CDS_SEC"1"
MATERIAL"EMPTY"
TOLERANCE"10%"
VALUE"560PF"
PACK_TYPE"C0402"
VOLTAGE"50V"
CDS_LIB"pure_quanta"
PART_NUMBER"CH1566K1B09";
"B"
$PN"2"49;
"A"
$PN"1"56;
%"Q_CAP"
"1","(-7675,6375)","0","pure_quanta","I58";
;
LOCATION"PC181_3"
$SEC"1"
CDS_SEC"1"
TOLERANCE"20%"
VOLTAGE"16V"
VALUE"22UF"
MATERIAL"X6S"
PACK_TYPE"C0805"
CDS_LIB"pure_quanta"
PART_NUMBER"CH6223MEA01";
"B"
$PN"2"14;
"A"
$PN"1"57;
%"Q_CAP"
"1","(-7050,5650)","0","pure_quanta","I59";
;
LOCATION"PC186"
$SEC"1"
CDS_SEC"1"
TOLERANCE"10%"
PACK_TYPE"0402"
VALUE"0.22UF"
MATERIAL"X7R"
VOLTAGE"16V"
CDS_LIB"pure_quanta"
PART_NUMBER"CH4223K1B00";
"B"
$PN"2"54;
"A"
$PN"1"17;
%"Q_CAP"
"1","(-7275,6375)","0","pure_quanta","I60";
;
LOCATION"PC184_3"
$SEC"1"
CDS_SEC"1"
TOLERANCE"20%"
VOLTAGE"16V"
VALUE"22UF"
MATERIAL"X6S"
PACK_TYPE"C0805"
CDS_LIB"pure_quanta"
PART_NUMBER"CH6223MEA01";
"B"
$PN"2"14;
"A"
$PN"1"57;
%"Q_INDUCTOR4P_14"
"1","(-6025,5300)","0","pure_quanta","I61";
;
LOCATION"PL21"
$SEC"1"
CDS_SEC"1"
MATERIAL"IND"
PART_TYPE"SMLF"
VALUE"150NH"
CDS_LIB"pure_quanta"
NEEDS_NO_SIZE"TRUE"
PART_NUMBER"CV+15^0TZ04";
"1"
$PN"1"56;
"4"
$PN"4"27;
"3"
$PN"3"51;
"2"
$PN"2"50;
%"UNIVERSAL_GND"
"1","(-6850,6000)","0","pure_quanta_power","I62";
;
CDS_LIB"pure_quanta_power"
HDL_POWER"GND";
"A"14;
%"Q_CAP"
"1","(-6850,6400)","0","pure_quanta","I63";
;
LOCATION"PC187_3"
$SEC"1"
CDS_SEC"1"
VALUE"22UF"
MATERIAL"X6S"
PACK_TYPE"C0805"
TOLERANCE"20%"
VOLTAGE"16V"
CDS_LIB"pure_quanta"
PART_NUMBER"CH6223MEA01";
"B"
$PN"2"14;
"A"
$PN"1"57;
%"VCC_CORE"
"1","(-6850,6750)","0","pure_quanta_power","I64";
;
HDL_POWER"SW_P12V_AUX_PVDDIO_P0_FLT"
CDS_LIB"pure_quanta_power";
"A"57;
%"Q_CAP"
"1","(-4150,5225)","0","pure_quanta","I66";
;
LOCATION"PC190_3"
$SEC"1"
CDS_SEC"1"
PACK_TYPE"C0805"
MATERIAL"X6S"
TOLERANCE"20%"
VALUE"22UF"
VOLTAGE"4V"
CDS_LIB"pure_quanta"
PART_NUMBER"CH622KMEA03";
"B"
$PN"2"26;
"A"
$PN"1"27;
%"UNIVERSAL_GND"
"1","(-3775,2075)","0","pure_quanta_power","I67";
;
CDS_LIB"pure_quanta_power"
HDL_POWER"GND";
"A"24;
%"Q_CAP"
"1","(-3775,2425)","0","pure_quanta","I68";
;
LOCATION"PC191_4"
$SEC"1"
CDS_SEC"1"
PACK_TYPE"C0805"
MATERIAL"X6S"
TOLERANCE"20%"
VALUE"22UF"
VOLTAGE"4V"
CDS_LIB"pure_quanta"
PART_NUMBER"CH622KMEA03";
"B"
$PN"2"24;
"A"
$PN"1"25;
%"VCC_CORE"
"1","(-3775,2750)","0","pure_quanta_power","I69";
;
HDL_POWER"PVDDIO_P0"
CDS_LIB"pure_quanta_power";
"A"25;
%"UNIVERSAL_GND"
"1","(-3725,4900)","0","pure_quanta_power","I70";
;
CDS_LIB"pure_quanta_power"
HDL_POWER"GND";
"A"26;
%"Q_CAP"
"1","(-3725,5225)","0","pure_quanta","I71";
;
LOCATION"PC192_3"
$SEC"1"
CDS_SEC"1"
PACK_TYPE"C0805"
MATERIAL"X6S"
TOLERANCE"20%"
VALUE"22UF"
VOLTAGE"4V"
CDS_LIB"pure_quanta"
PART_NUMBER"CH622KMEA03";
"B"
$PN"2"26;
"A"
$PN"1"27;
%"VCC_CORE"
"1","(-3725,5550)","0","pure_quanta_power","I72";
;
HDL_POWER"PVDDIO_P0"
CDS_LIB"pure_quanta_power";
"A"27;
%"ISL99390FRZTR5935"
"1","(-9350,2625)","0","pure_quanta","I73";
;
LOCATION"PU20"
$SEC"1"
CDS_SEC"1"
VALUE"ISL99390FRZ-TR5935"
MATERIAL"IC"
PART_TYPE"SMLF"
NEEDS_NO_SIZE"TRUE"
CDS_LMAN_SYM_OUTLINE"-300,700,250,-650"
CDS_LIB"pure_quanta"
PART_NUMBER"AL099390004";
"PGND2"
$PN"7_9-20_24"21;
"GL2"
$PN"41"37;
"GL1"
$PN"6"36;
"DNC"
$PN"31"33;
"EN"
$PN"35"39;
"PGND3"
$PN"40"21;
"VOS"
$PN"1"38;
"VIN2"
$PN"30"12;
"PGND1"
$PN"5"21;
"SW"
$PN"10_19"52;
"LSET"
$PN"37"30;
"IOUT"
$PN"38"35;
"TOUT_FLT"
$PN"36"32;
"PVCC"
$PN"4"20;
"PHASE"
$PN"32"53;
"VIN1"
$PN"25_29"12;
"BOOT"
$PN"33"18;
"AGND"
$PN"2"21;
"VCC"
$PN"3"39;
"REFIN"
$PN"39"31;
"PWM"
$PN"34"34;
%"UNIVERSAL_GND"
"1","(-11050,2825)","0","pure_quanta_power","I9";
;
CDS_LIB"pure_quanta_power"
HDL_POWER"GND";
"A"11;
END.
